(kicad_pcb
	(version 20260206)
	(generator "pcbnew")
	(generator_version "10.0")
	(general
		(thickness 1.6)
		(legacy_teardrops no)
	)
	(paper "A4")
	(title_block
		(title "Wiwynn_Tioga_Pass_MB.brd")
		(comment 1 "Tioga Pass / footprints 4503-4510 of 4770")
	)
	(layers
		(0 "F.Cu" signal "TOP")
		(4 "In1.Cu" signal "L2GND")
		(6 "In2.Cu" signal "L3")
		(8 "In3.Cu" signal "L4GND")
		(10 "In4.Cu" signal "L5")
		(12 "In5.Cu" signal "L6GND")
		(14 "In6.Cu" signal "L7VCC")
		(16 "In7.Cu" signal "L8VCC")
		(18 "In8.Cu" signal "L9GND")
		(20 "In9.Cu" signal "L10")
		(22 "In10.Cu" signal "L11GND")
		(24 "In11.Cu" signal "L12")
		(26 "In12.Cu" signal "L13GND")
		(2 "B.Cu" signal "BOTTOM")
		(9 "F.Adhes" user "F.Adhesive")
		(11 "B.Adhes" user "B.Adhesive")
		(13 "F.Paste" user "Package Geometry/Pastemask Top")
		(15 "B.Paste" user "Package Geometry/Pastemask Bottom")
		(5 "F.SilkS" user "Ref Des/Silkscreen Top")
		(7 "B.SilkS" user "Ref Des/Silkscreen Bottom")
		(1 "F.Mask" user "Board Geometry/Soldermask Top")
		(3 "B.Mask" user "Board Geometry/Soldermask Bottom")
		(17 "Dwgs.User" user "User.Drawings")
		(19 "Cmts.User" user "User.Comments")
		(21 "Eco1.User" user "User.Eco1")
		(23 "Eco2.User" user "User.Eco2")
		(25 "Edge.Cuts" user "Board Geometry/Outline")
		(27 "Margin" user)
		(31 "F.CrtYd" user "Package Geometry/Place Bound Top")
		(29 "B.CrtYd" user "Package Geometry/Place Bound Bottom")
		(35 "F.Fab" user "Ref Des/Assembly Top")
		(33 "B.Fab" user "Ref Des/Assembly Bottom")
	)
	(footprint ""
		(layer "B.Cu")
		(at 197.848728 -66.327782 90)
		(property "Reference" "C6P24"
			(at 0 0 90)
			(layer "B.SilkS")
			(hide yes)
			(effects
				(font
					(size 1.27 1.27)
				)
				(justify mirror)
			)
		)
		(property "Value" ""
			(at 0 0 90)
			(layer "B.Fab")
			(effects
				(font
					(size 1.27 1.27)
				)
				(justify mirror)
			)
		)
		(duplicate_pad_numbers_are_jumpers no)
		(fp_rect
			(start 0.7239 1.9939)
			(end -0.7239 -0.2159)
			(stroke
				(width 0)
				(type default)
			)
			(fill no)
			(layer "B.CrtYd")
		)
		(fp_line
			(start 0.7239 -0.2159)
			(end 0.7239 1.9939)
			(stroke
				(width 0.1)
				(type default)
			)
			(layer "B.Fab")
		)
		(fp_line
			(start -0.7239 -0.2159)
			(end 0.7239 -0.2159)
			(stroke
				(width 0.1)
				(type default)
			)
			(layer "B.Fab")
		)
		(fp_line
			(start 0.7239 1.9939)
			(end -0.7239 1.9939)
			(stroke
				(width 0.1)
				(type default)
			)
			(layer "B.Fab")
		)
		(fp_line
			(start -0.7239 1.9939)
			(end -0.7239 -0.2159)
			(stroke
				(width 0.1)
				(type default)
			)
			(layer "B.Fab")
		)
		(pad "1" smd rect
			(at 0 0 270)
			(size 1.27 1.016)
			(layers "B.Cu" "B.Mask" "B.Paste")
			(net "VR_FET_SW_P12V_STBY_PVCCIN_CPU0")
		)
		(pad "2" smd rect
			(at 0 1.778 270)
			(size 1.27 1.016)
			(layers "B.Cu" "B.Mask" "B.Paste")
			(net "GND")
		)
		(zone
			(layer "B.Cu")
			(hatch none 0.5)
			(connect_pads
				(clearance 0)
			)
			(min_thickness 0.25)
			(keepout
				(tracks not_allowed)
				(vias allowed)
				(pads allowed)
				(copperpour not_allowed)
				(footprints allowed)
			)
			(placement
				(enabled no)
				(sheetname "")
			)
			(fill
				(thermal_gap 0.5)
				(thermal_bridge_width 0.5)
				(island_removal_mode 0)
			)
			(polygon
				(pts
					(xy 199.118728 -66.962782) (xy 198.356728 -66.962782) (xy 198.356728 -65.692782) (xy 199.118728 -65.692782)
				)
			)
		)
	)
	(footprint ""
		(layer "B.Cu")
		(at 388.366 -129.99974 180)
		(property "Reference" "R3M8"
			(at 0 0 0)
			(layer "B.SilkS")
			(hide yes)
			(effects
				(font
					(size 1.27 1.27)
				)
				(justify mirror)
			)
		)
		(property "Value" ""
			(at 0 0 0)
			(layer "B.Fab")
			(effects
				(font
					(size 1.27 1.27)
				)
				(justify mirror)
			)
		)
		(duplicate_pad_numbers_are_jumpers no)
		(fp_poly
			(pts
				(xy 0.2794 -0.1016) (xy -0.2794 -0.1016) (xy -0.2794 0.9906) (xy 0.2794 0.9906)
			)
			(stroke
				(width 0)
				(type default)
			)
			(fill no)
			(layer "B.CrtYd")
		)
		(fp_line
			(start 0.2794 0.9906)
			(end -0.2794 0.9906)
			(stroke
				(width 0.1)
				(type default)
			)
			(layer "B.Fab")
		)
		(fp_line
			(start 0.2794 -0.1016)
			(end 0.2794 0.9906)
			(stroke
				(width 0.1)
				(type default)
			)
			(layer "B.Fab")
		)
		(fp_line
			(start -0.2794 0.9906)
			(end -0.2794 -0.1016)
			(stroke
				(width 0.1)
				(type default)
			)
			(layer "B.Fab")
		)
		(fp_line
			(start -0.2794 -0.1016)
			(end 0.2794 -0.1016)
			(stroke
				(width 0.1)
				(type default)
			)
			(layer "B.Fab")
		)
		(pad "1" smd rect
			(at 0 0)
			(size 0.508 0.508)
			(layers "B.Cu" "B.Mask" "B.Paste")
			(net "P2E_SSB_BMC_RX_C_DP")
		)
		(pad "2" smd rect
			(at 0 0.889)
			(size 0.508 0.508)
			(layers "B.Cu" "B.Mask" "B.Paste")
			(net "GND")
		)
		(zone
			(layer "B.Cu")
			(hatch none 0.5)
			(connect_pads
				(clearance 0)
			)
			(min_thickness 0.25)
			(keepout
				(tracks not_allowed)
				(vias allowed)
				(pads allowed)
				(copperpour not_allowed)
				(footprints allowed)
			)
			(placement
				(enabled no)
				(sheetname "")
			)
			(fill
				(thermal_gap 0.5)
				(thermal_bridge_width 0.5)
				(island_removal_mode 0)
			)
			(polygon
				(pts
					(xy 388.112 -130.63474) (xy 388.62 -130.63474) (xy 388.62 -130.25374) (xy 388.112 -130.25374)
				)
			)
		)
		(zone
			(layer "B.Cu")
			(hatch none 0.5)
			(connect_pads
				(clearance 0)
			)
			(min_thickness 0.25)
			(keepout
				(tracks allowed)
				(vias not_allowed)
				(pads allowed)
				(copperpour not_allowed)
				(footprints allowed)
			)
			(placement
				(enabled no)
				(sheetname "")
			)
			(fill
				(thermal_gap 0.5)
				(thermal_bridge_width 0.5)
				(island_removal_mode 0)
			)
			(polygon
				(pts
					(xy 388.112 -130.25374) (xy 388.62 -130.25374) (xy 388.62 -130.63474) (xy 388.112 -130.63474)
				)
			)
		)
	)
	(footprint ""
		(layer "B.Cu")
		(at 320.294 -154.813 90)
		(property "Reference" "C4L1"
			(at 0 0 90)
			(layer "B.SilkS")
			(hide yes)
			(effects
				(font
					(size 1.27 1.27)
				)
				(justify mirror)
			)
		)
		(property "Value" ""
			(at 0 0 90)
			(layer "B.Fab")
			(effects
				(font
					(size 1.27 1.27)
				)
				(justify mirror)
			)
		)
		(duplicate_pad_numbers_are_jumpers no)
		(fp_poly
			(pts
				(xy 0.4953 -0.2032) (xy -0.4953 -0.2032) (xy -0.4953 1.6002) (xy 0.4953 1.6002)
			)
			(stroke
				(width 0)
				(type default)
			)
			(fill no)
			(layer "B.CrtYd")
		)
		(fp_line
			(start 0.4953 -0.2032)
			(end -0.4953 -0.2032)
			(stroke
				(width 0.1)
				(type default)
			)
			(layer "B.Fab")
		)
		(fp_line
			(start -0.4953 -0.2032)
			(end -0.4953 1.6002)
			(stroke
				(width 0.1)
				(type default)
			)
			(layer "B.Fab")
		)
		(fp_line
			(start 0.4953 1.6002)
			(end 0.4953 -0.2032)
			(stroke
				(width 0.1)
				(type default)
			)
			(layer "B.Fab")
		)
		(fp_line
			(start -0.4953 1.6002)
			(end 0.4953 1.6002)
			(stroke
				(width 0.1)
				(type default)
			)
			(layer "B.Fab")
		)
		(pad "1" smd rect
			(at 0 0 270)
			(size 0.762 0.889)
			(layers "B.Cu" "B.Mask" "B.Paste")
			(net "PVPP_DEF")
		)
		(pad "2" smd rect
			(at 0 1.397 270)
			(size 0.762 0.889)
			(layers "B.Cu" "B.Mask" "B.Paste")
			(net "GND")
		)
		(zone
			(layer "B.Cu")
			(hatch none 0.5)
			(connect_pads
				(clearance 0)
			)
			(min_thickness 0.25)
			(keepout
				(tracks not_allowed)
				(vias allowed)
				(pads allowed)
				(copperpour not_allowed)
				(footprints allowed)
			)
			(placement
				(enabled no)
				(sheetname "")
			)
			(fill
				(thermal_gap 0.5)
				(thermal_bridge_width 0.5)
				(island_removal_mode 0)
			)
			(polygon
				(pts
					(xy 320.7385 -155.194) (xy 320.7385 -154.432) (xy 321.2465 -154.432) (xy 321.2465 -155.194)
				)
			)
		)
	)
	(footprint ""
		(layer "B.Cu")
		(at 446.912238 -52.407058)
		(property "Reference" "C2R14"
			(at 0 0 0)
			(layer "B.SilkS")
			(hide yes)
			(effects
				(font
					(size 1.27 1.27)
				)
				(justify mirror)
			)
		)
		(property "Value" ""
			(at 0 0 0)
			(layer "B.Fab")
			(effects
				(font
					(size 1.27 1.27)
				)
				(justify mirror)
			)
		)
		(duplicate_pad_numbers_are_jumpers no)
		(fp_poly
			(pts
				(xy -0.3048 -0.1016) (xy -0.3048 0.9906) (xy 0.3048 0.9906) (xy 0.3048 -0.1016)
			)
			(stroke
				(width 0)
				(type default)
			)
			(fill no)
			(layer "B.CrtYd")
		)
		(fp_line
			(start -0.3048 -0.1016)
			(end 0.3048 -0.1016)
			(stroke
				(width 0.1)
				(type default)
			)
			(layer "B.Fab")
		)
		(fp_line
			(start -0.3048 0.9906)
			(end -0.3048 -0.1016)
			(stroke
				(width 0.1)
				(type default)
			)
			(layer "B.Fab")
		)
		(fp_line
			(start 0.3048 -0.1016)
			(end 0.3048 0.9906)
			(stroke
				(width 0.1)
				(type default)
			)
			(layer "B.Fab")
		)
		(fp_line
			(start 0.3048 0.9906)
			(end -0.3048 0.9906)
			(stroke
				(width 0.1)
				(type default)
			)
			(layer "B.Fab")
		)
		(pad "1" smd rect
			(at 0 0 180)
			(size 0.508 0.508)
			(layers "B.Cu" "B.Mask" "B.Paste")
			(net "P3E_CPU0_PE3_OCP_TXP<5>")
		)
		(pad "2" smd rect
			(at 0 0.889 180)
			(size 0.508 0.508)
			(layers "B.Cu" "B.Mask" "B.Paste")
			(net "P3E_OCP_CPU0_PE3_C_TXP<5>")
		)
		(zone
			(layer "B.Cu")
			(hatch none 0.5)
			(connect_pads
				(clearance 0)
			)
			(min_thickness 0.25)
			(keepout
				(tracks allowed)
				(vias not_allowed)
				(pads allowed)
				(copperpour not_allowed)
				(footprints allowed)
			)
			(placement
				(enabled no)
				(sheetname "")
			)
			(fill
				(thermal_gap 0.5)
				(thermal_bridge_width 0.5)
				(island_removal_mode 0)
			)
			(polygon
				(pts
					(xy 447.166238 -52.153058) (xy 446.658238 -52.153058) (xy 446.658238 -51.772058) (xy 447.166238 -51.772058)
				)
			)
		)
		(zone
			(layer "B.Cu")
			(hatch none 0.5)
			(connect_pads
				(clearance 0)
			)
			(min_thickness 0.25)
			(keepout
				(tracks not_allowed)
				(vias allowed)
				(pads allowed)
				(copperpour not_allowed)
				(footprints allowed)
			)
			(placement
				(enabled no)
				(sheetname "")
			)
			(fill
				(thermal_gap 0.5)
				(thermal_bridge_width 0.5)
				(island_removal_mode 0)
			)
			(polygon
				(pts
					(xy 447.166238 -51.772058) (xy 446.658238 -51.772058) (xy 446.658238 -52.153058) (xy 447.166238 -52.153058)
				)
			)
		)
	)
	(footprint ""
		(layer "B.Cu")
		(at 482.65969 -58.831988 -90)
		(property "Reference" "R8E26"
			(at 0 0 90)
			(layer "B.SilkS")
			(hide yes)
			(effects
				(font
					(size 1.27 1.27)
				)
				(justify mirror)
			)
		)
		(property "Value" ""
			(at 0 0 90)
			(layer "B.Fab")
			(effects
				(font
					(size 1.27 1.27)
				)
				(justify mirror)
			)
		)
		(duplicate_pad_numbers_are_jumpers no)
		(fp_poly
			(pts
				(xy 0.2794 -0.1016) (xy -0.2794 -0.1016) (xy -0.2794 0.9906) (xy 0.2794 0.9906)
			)
			(stroke
				(width 0)
				(type default)
			)
			(fill no)
			(layer "B.CrtYd")
		)
		(fp_line
			(start -0.2794 0.9906)
			(end -0.2794 -0.1016)
			(stroke
				(width 0.1)
				(type default)
			)
			(layer "B.Fab")
		)
		(fp_line
			(start 0.2794 0.9906)
			(end -0.2794 0.9906)
			(stroke
				(width 0.1)
				(type default)
			)
			(layer "B.Fab")
		)
		(fp_line
			(start -0.2794 -0.1016)
			(end 0.2794 -0.1016)
			(stroke
				(width 0.1)
				(type default)
			)
			(layer "B.Fab")
		)
		(fp_line
			(start 0.2794 -0.1016)
			(end 0.2794 0.9906)
			(stroke
				(width 0.1)
				(type default)
			)
			(layer "B.Fab")
		)
		(pad "1" smd rect
			(at 0 0 90)
			(size 0.508 0.508)
			(layers "B.Cu" "B.Mask" "B.Paste")
			(net "FM_PE_OCP_WAKE_N")
		)
		(pad "2" smd rect
			(at 0 0.889 90)
			(size 0.508 0.508)
			(layers "B.Cu" "B.Mask" "B.Paste")
			(net "FM_ALL_WAKE_N")
		)
		(zone
			(layer "B.Cu")
			(hatch none 0.5)
			(connect_pads
				(clearance 0)
			)
			(min_thickness 0.25)
			(keepout
				(tracks not_allowed)
				(vias allowed)
				(pads allowed)
				(copperpour not_allowed)
				(footprints allowed)
			)
			(placement
				(enabled no)
				(sheetname "")
			)
			(fill
				(thermal_gap 0.5)
				(thermal_bridge_width 0.5)
				(island_removal_mode 0)
			)
			(polygon
				(pts
					(xy 482.02469 -58.577988) (xy 482.02469 -59.085988) (xy 482.40569 -59.085988) (xy 482.40569 -58.577988)
				)
			)
		)
		(zone
			(layer "B.Cu")
			(hatch none 0.5)
			(connect_pads
				(clearance 0)
			)
			(min_thickness 0.25)
			(keepout
				(tracks allowed)
				(vias not_allowed)
				(pads allowed)
				(copperpour not_allowed)
				(footprints allowed)
			)
			(placement
				(enabled no)
				(sheetname "")
			)
			(fill
				(thermal_gap 0.5)
				(thermal_bridge_width 0.5)
				(island_removal_mode 0)
			)
			(polygon
				(pts
					(xy 482.40569 -58.577988) (xy 482.40569 -59.085988) (xy 482.02469 -59.085988) (xy 482.02469 -58.577988)
				)
			)
		)
	)
	(footprint ""
		(layer "B.Cu")
		(at 446.292478 -152.855168)
		(property "Reference" "R25W179"
			(at 0.8382 -0.67818 0)
			(unlocked yes)
			(layer "B.SilkS")
			(effects
				(font
					(size 0.4064 0.254)
					(thickness 0.1524)
				)
				(justify left mirror)
			)
		)
		(property "Value" ""
			(at 0 0 0)
			(layer "B.Fab")
			(effects
				(font
					(size 1.27 1.27)
				)
				(justify mirror)
			)
		)
		(duplicate_pad_numbers_are_jumpers no)
		(fp_poly
			(pts
				(xy 0.2794 -0.1016) (xy -0.2794 -0.1016) (xy -0.2794 0.9906) (xy 0.2794 0.9906)
			)
			(stroke
				(width 0)
				(type default)
			)
			(fill no)
			(layer "B.CrtYd")
		)
		(fp_line
			(start -0.2794 -0.1016)
			(end 0.2794 -0.1016)
			(stroke
				(width 0.1)
				(type default)
			)
			(layer "B.Fab")
		)
		(fp_line
			(start -0.2794 0.9906)
			(end -0.2794 -0.1016)
			(stroke
				(width 0.1)
				(type default)
			)
			(layer "B.Fab")
		)
		(fp_line
			(start 0.2794 -0.1016)
			(end 0.2794 0.9906)
			(stroke
				(width 0.1)
				(type default)
			)
			(layer "B.Fab")
		)
		(fp_line
			(start 0.2794 0.9906)
			(end -0.2794 0.9906)
			(stroke
				(width 0.1)
				(type default)
			)
			(layer "B.Fab")
		)
		(pad "1" smd rect
			(at 0 0 180)
			(size 0.508 0.508)
			(layers "B.Cu" "B.Mask" "B.Paste")
			(net "P3V3_STBY")
		)
		(pad "2" smd rect
			(at 0 0.889 180)
			(size 0.508 0.508)
			(layers "B.Cu" "B.Mask" "B.Paste")
			(net "XDP_PRESENT_N")
		)
		(zone
			(layer "B.Cu")
			(hatch none 0.5)
			(connect_pads
				(clearance 0)
			)
			(min_thickness 0.25)
			(keepout
				(tracks allowed)
				(vias not_allowed)
				(pads allowed)
				(copperpour not_allowed)
				(footprints allowed)
			)
			(placement
				(enabled no)
				(sheetname "")
			)
			(fill
				(thermal_gap 0.5)
				(thermal_bridge_width 0.5)
				(island_removal_mode 0)
			)
			(polygon
				(pts
					(xy 446.546478 -152.601168) (xy 446.038478 -152.601168) (xy 446.038478 -152.220168) (xy 446.546478 -152.220168)
				)
			)
		)
		(zone
			(layer "B.Cu")
			(hatch none 0.5)
			(connect_pads
				(clearance 0)
			)
			(min_thickness 0.25)
			(keepout
				(tracks not_allowed)
				(vias allowed)
				(pads allowed)
				(copperpour not_allowed)
				(footprints allowed)
			)
			(placement
				(enabled no)
				(sheetname "")
			)
			(fill
				(thermal_gap 0.5)
				(thermal_bridge_width 0.5)
				(island_removal_mode 0)
			)
			(polygon
				(pts
					(xy 446.546478 -152.220168) (xy 446.038478 -152.220168) (xy 446.038478 -152.601168) (xy 446.546478 -152.601168)
				)
			)
		)
	)
	(footprint ""
		(layer "B.Cu")
		(at -2.20726 -117.89156)
		(property "Reference" "R9M18"
			(at 0 0 0)
			(layer "B.SilkS")
			(hide yes)
			(effects
				(font
					(size 1.27 1.27)
				)
				(justify mirror)
			)
		)
		(property "Value" ""
			(at 0 0 0)
			(layer "B.Fab")
			(effects
				(font
					(size 1.27 1.27)
				)
				(justify mirror)
			)
		)
		(duplicate_pad_numbers_are_jumpers no)
		(fp_rect
			(start -0.2794 0.9906)
			(end 0.2794 -0.1016)
			(stroke
				(width 0)
				(type default)
			)
			(fill no)
			(layer "B.CrtYd")
		)
		(fp_line
			(start -0.2794 -0.1016)
			(end 0.2794 -0.1016)
			(stroke
				(width 0.1)
				(type default)
			)
			(layer "B.Fab")
		)
		(fp_line
			(start -0.2794 0.9906)
			(end -0.2794 -0.1016)
			(stroke
				(width 0.1)
				(type default)
			)
			(layer "B.Fab")
		)
		(fp_line
			(start 0.2794 -0.1016)
			(end 0.2794 0.9906)
			(stroke
				(width 0.1)
				(type default)
			)
			(layer "B.Fab")
		)
		(fp_line
			(start 0.2794 0.9906)
			(end -0.2794 0.9906)
			(stroke
				(width 0.1)
				(type default)
			)
			(layer "B.Fab")
		)
		(pad "1" smd rect
			(at 0 0 180)
			(size 0.508 0.508)
			(layers "B.Cu" "B.Mask" "B.Paste")
			(net "PVCCIO_CPU1")
		)
		(pad "2" smd rect
			(at 0 0.889 180)
			(size 0.508 0.508)
			(layers "B.Cu" "B.Mask" "B.Paste")
			(net "SMB_CPU1_PE_HP_GTL_R_SDA")
		)
		(zone
			(layer "B.Cu")
			(hatch none 0.5)
			(connect_pads
				(clearance 0)
			)
			(min_thickness 0.25)
			(keepout
				(tracks not_allowed)
				(vias allowed)
				(pads allowed)
				(copperpour not_allowed)
				(footprints allowed)
			)
			(placement
				(enabled no)
				(sheetname "")
			)
			(fill
				(thermal_gap 0.5)
				(thermal_bridge_width 0.5)
				(island_removal_mode 0)
			)
			(polygon
				(pts
					(xy -2.46126 -117.25656) (xy -1.95326 -117.25656) (xy -1.95326 -117.63756) (xy -2.46126 -117.63756)
				)
			)
		)
		(zone
			(layer "B.Cu")
			(hatch none 0.5)
			(connect_pads
				(clearance 0)
			)
			(min_thickness 0.25)
			(keepout
				(tracks allowed)
				(vias not_allowed)
				(pads allowed)
				(copperpour not_allowed)
				(footprints allowed)
			)
			(placement
				(enabled no)
				(sheetname "")
			)
			(fill
				(thermal_gap 0.5)
				(thermal_bridge_width 0.5)
				(island_removal_mode 0)
			)
			(polygon
				(pts
					(xy -2.46126 -117.25656) (xy -1.95326 -117.25656) (xy -1.95326 -117.63756) (xy -2.46126 -117.63756)
				)
			)
		)
	)
	(footprint ""
		(layer "B.Cu")
		(at 186.69 -99.695)
		(property "Reference" ""
			(at 0 0 0)
			(layer "B.SilkS")
			(hide yes)
			(effects
				(font
					(size 1.27 1.27)
				)
				(justify mirror)
			)
		)
		(property "Value" ""
			(at 0 0 0)
			(layer "B.Fab")
			(effects
				(font
					(size 1.27 1.27)
				)
				(justify mirror)
			)
		)
		(duplicate_pad_numbers_are_jumpers no)
		(fp_poly
			(pts
				(arc
					(start 2.032 0)
					(mid -2.032 0)
					(end 2.032 0)
				)
			)
			(stroke
				(width 0)
				(type default)
			)
			(fill no)
			(layer "B.CrtYd")
		)
		(pad "1" smd circle
			(at 0 0 180)
			(size 1.016 1.016)
			(layers "B.Cu" "B.Mask" "B.Paste")
			(net "Net_392")
		)
		(zone
			(layers "F.Cu" "B.Cu" "In1.Cu" "In2.Cu" "In3.Cu" "In4.Cu" "In5.Cu" "In6.Cu"
				"In7.Cu" "In8.Cu" "In9.Cu" "In10.Cu" "In11.Cu" "In12.Cu"
			)
			(hatch none 0.5)
			(connect_pads
				(clearance 0)
			)
			(min_thickness 0.25)
			(keepout
				(tracks allowed)
				(vias not_allowed)
				(pads allowed)
				(copperpour not_allowed)
				(footprints allowed)
			)
			(placement
				(enabled no)
				(sheetname "")
			)
			(fill
				(thermal_gap 0.5)
				(thermal_bridge_width 0.5)
				(island_removal_mode 0)
			)
			(polygon
				(pts
					(arc
						(start 188.214 -99.695)
						(mid 185.166 -99.695)
						(end 188.214 -99.695)
					)
				)
			)
		)
		(zone
			(layer "B.Cu")
			(hatch none 0.5)
			(connect_pads
				(clearance 0)
			)
			(min_thickness 0.25)
			(keepout
				(tracks not_allowed)
				(vias allowed)
				(pads allowed)
				(copperpour not_allowed)
				(footprints allowed)
			)
			(placement
				(enabled no)
				(sheetname "")
			)
			(fill
				(thermal_gap 0.5)
				(thermal_bridge_width 0.5)
				(island_removal_mode 0)
			)
			(polygon
				(pts
					(arc
						(start 188.214 -99.695)
						(mid 185.166 -99.695)
						(end 188.214 -99.695)
					)
				)
			)
		)
	)
)
